(kicad_pcb
	(version 20240108)
	(generator "pcbnew")
	(generator_version "8.0")
	(general
		(thickness 1.6)
		(legacy_teardrops no)
	)
	(paper "A4")
	(title_block
		(title "Jetson Orin Baseboard OCuLink Expansion")
		(date "2025-03-18")
		(rev "1.1.0")
		(company "Antmicro Ltd")
		(comment 1 "www.antmicro.com")
		(comment 9 "footprints 72-77 of 119")
	)
	(layers
		(0 "F.Cu" signal)
		(1 "In1.Cu" signal)
		(2 "In2.Cu" signal)
		(31 "B.Cu" signal)
		(32 "B.Adhes" user "B.Adhesive")
		(33 "F.Adhes" user "F.Adhesive")
		(34 "B.Paste" user)
		(35 "F.Paste" user)
		(36 "B.SilkS" user "B.Silkscreen")
		(37 "F.SilkS" user "F.Silkscreen")
		(38 "B.Mask" user)
		(39 "F.Mask" user)
		(40 "Dwgs.User" user "User.Drawings")
		(41 "Cmts.User" user "User.Comments")
		(42 "Eco1.User" user "User.Eco1")
		(43 "Eco2.User" user "User.Eco2")
		(44 "Edge.Cuts" user)
		(45 "Margin" user)
		(46 "B.CrtYd" user "B.Courtyard")
		(47 "F.CrtYd" user "F.Courtyard")
		(48 "B.Fab" user)
		(49 "F.Fab" user)
	)
	(footprint "antmicro-footprints:R_0402_1005Metric"
		(layer "B.Cu")
		(at 116.475 113.973751)
		(descr "Resistor SMD 0402")
		(tags "resistor SMD 0402")
		(property "Reference" "R5"
			(at -2.585 -0.383751 0)
			(layer "B.SilkS")
			(effects
				(font
					(size 0.7 0.7)
					(thickness 0.15)
				)
				(justify right top mirror)
			)
		)
		(property "Value" "R_1k_0402"
			(at -1.011843 -1.772047 0)
			(layer "B.Fab")
			(effects
				(font
					(size 0.7 0.7)
					(thickness 0.15)
				)
				(justify right top mirror)
			)
		)
		(property "Footprint" "antmicro-footprints:R_0402_1005Metric"
			(at 0 0 0)
			(layer "B.Fab")
			(hide yes)
			(effects
				(font
					(size 1.27 1.27)
					(thickness 0.15)
				)
				(justify mirror)
			)
		)
		(property "Datasheet" "https://www.bourns.com/docs/product-datasheets/cr.pdf"
			(at 0 0 0)
			(layer "B.Fab")
			(hide yes)
			(effects
				(font
					(size 1.27 1.27)
					(thickness 0.15)
				)
				(justify mirror)
			)
		)
		(property "Description" "SMD Chip Resistor, 1 kohm, ± 1%, 63 mW, 0402 [1005 Metric], Thick Film, General Purpose"
			(at 0 0 0)
			(layer "B.Fab")
			(hide yes)
			(effects
				(font
					(size 1.27 1.27)
					(thickness 0.15)
				)
				(justify mirror)
			)
		)
		(property "MPN" "CR0402-FX-1001GLF"
			(at 0 0 180)
			(unlocked yes)
			(layer "B.Fab")
			(hide yes)
			(effects
				(font
					(size 1 1)
					(thickness 0.15)
				)
				(justify mirror)
			)
		)
		(property "Manufacturer" "Bourns"
			(at 0 0 180)
			(unlocked yes)
			(layer "B.Fab")
			(hide yes)
			(effects
				(font
					(size 1 1)
					(thickness 0.15)
				)
				(justify mirror)
			)
		)
		(property "License" "Apache-2.0"
			(at 0 0 180)
			(unlocked yes)
			(layer "B.Fab")
			(hide yes)
			(effects
				(font
					(size 1 1)
					(thickness 0.15)
				)
				(justify mirror)
			)
		)
		(property "Author" "Antmicro"
			(at 0 0 180)
			(unlocked yes)
			(layer "B.Fab")
			(hide yes)
			(effects
				(font
					(size 1 1)
					(thickness 0.15)
				)
				(justify mirror)
			)
		)
		(property "Val" "1k"
			(at 0 0 180)
			(unlocked yes)
			(layer "B.Fab")
			(hide yes)
			(effects
				(font
					(size 1 1)
					(thickness 0.15)
				)
				(justify mirror)
			)
		)
		(property "Tolerance" "1%"
			(at 0 0 180)
			(unlocked yes)
			(layer "B.Fab")
			(hide yes)
			(effects
				(font
					(size 1 1)
					(thickness 0.15)
				)
				(justify mirror)
			)
		)
		(property "Public" "False"
			(at 0 0 180)
			(unlocked yes)
			(layer "B.Fab")
			(hide yes)
			(effects
				(font
					(size 1 1)
					(thickness 0.15)
				)
				(justify mirror)
			)
		)
		(sheetname "Root")
		(sheetfile "jetson-orin-baseboard-oculink-expansion.kicad_sch")
		(attr smd)
		(fp_rect
			(start -0.925 0.47)
			(end 0.925 -0.47)
			(stroke
				(width 0.05)
				(type default)
			)
			(fill none)
			(layer "B.CrtYd")
		)
		(fp_rect
			(start -0.5 0.25)
			(end 0.5 -0.25)
			(stroke
				(width 0.15)
				(type solid)
			)
			(fill none)
			(layer "B.Fab")
		)
		(fp_text user "Author: Antmicro"
			(at -0.95 -4.169 0)
			(layer "B.Fab")
			(hide yes)
			(effects
				(font
					(size 0.7 0.7)
					(thickness 0.15)
				)
				(justify right top mirror)
			)
		)
		(fp_text user "${REFERENCE}"
			(at -0.95 -3.168 0)
			(layer "B.Fab")
			(hide yes)
			(effects
				(font
					(size 0.7 0.7)
					(thickness 0.15)
				)
				(justify right top mirror)
			)
		)
		(fp_text user "License: Apache-2.0"
			(at -0.95 -5.169 0)
			(layer "B.Fab")
			(hide yes)
			(effects
				(font
					(size 0.7 0.7)
					(thickness 0.15)
				)
				(justify right top mirror)
			)
		)
		(pad "1" smd roundrect
			(at -0.48 0)
			(size 0.59 0.64)
			(layers "B.Cu" "B.Paste" "B.Mask")
			(roundrect_rratio 0.25)
			(net 51 "GND")
			(pintype "passive")
		)
		(pad "2" smd roundrect
			(at 0.48 0)
			(size 0.59 0.64)
			(layers "B.Cu" "B.Paste" "B.Mask")
			(roundrect_rratio 0.25)
			(net 89 "/RX_EQ0")
			(pintype "passive")
		)
	)
	(footprint "antmicro-footprints:TP_SMD_1.5mm"
		(layer "B.Cu")
		(at 142.3 141.324 180)
		(property "Reference" "TP5"
			(at -0.9 -8.12036 0)
			(layer "B.SilkS")
			(hide yes)
			(effects
				(font
					(size 0.7 0.7)
					(thickness 0.15)
				)
				(justify left bottom mirror)
			)
		)
		(property "Value" "TP_1.5mm_SMD"
			(at 1.522222 -0.978488 0)
			(layer "B.Fab")
			(effects
				(font
					(size 0.7 0.7)
					(thickness 0.15)
				)
				(justify left bottom mirror)
			)
		)
		(property "Footprint" "antmicro-footprints:TP_SMD_1.5mm"
			(at 0 0 0)
			(layer "B.Fab")
			(hide yes)
			(effects
				(font
					(size 1.27 1.27)
					(thickness 0.15)
				)
				(justify mirror)
			)
		)
		(property "Description" "test point, SMT"
			(at 0 0 0)
			(layer "B.Fab")
			(hide yes)
			(effects
				(font
					(size 1.27 1.27)
					(thickness 0.15)
				)
				(justify mirror)
			)
		)
		(property "MPN" ""
			(at 0 0 0)
			(unlocked yes)
			(layer "B.Fab")
			(hide yes)
			(effects
				(font
					(size 1 1)
					(thickness 0.15)
				)
				(justify mirror)
			)
		)
		(property "Manufacturer" ""
			(at 0 0 0)
			(unlocked yes)
			(layer "B.Fab")
			(hide yes)
			(effects
				(font
					(size 1 1)
					(thickness 0.15)
				)
				(justify mirror)
			)
		)
		(property "Author" "Antmicro"
			(at 0 0 0)
			(unlocked yes)
			(layer "B.Fab")
			(hide yes)
			(effects
				(font
					(size 1 1)
					(thickness 0.15)
				)
				(justify mirror)
			)
		)
		(property "License" "Apache-2.0"
			(at 0 0 0)
			(unlocked yes)
			(layer "B.Fab")
			(hide yes)
			(effects
				(font
					(size 1 1)
					(thickness 0.15)
				)
				(justify mirror)
			)
		)
		(sheetname "Root")
		(sheetfile "jetson-orin-baseboard-oculink-expansion.kicad_sch")
		(attr exclude_from_pos_files exclude_from_bom)
		(fp_circle
			(center 0 0)
			(end 0.85 0)
			(stroke
				(width 0.05)
				(type default)
			)
			(fill none)
			(layer "B.CrtYd")
		)
		(fp_text user "Author: Antmicro"
			(at -0.7 -4.101 0)
			(layer "B.Fab")
			(hide yes)
			(effects
				(font
					(size 0.7 0.7)
					(thickness 0.15)
				)
				(justify left bottom mirror)
			)
		)
		(fp_text user "License: Apache-2.0"
			(at -0.7 -5.301 0)
			(layer "B.Fab")
			(hide yes)
			(effects
				(font
					(size 0.7 0.7)
					(thickness 0.15)
				)
				(justify left bottom mirror)
			)
		)
		(fp_text user "${REFERENCE}"
			(at -0.7 -2.9 0)
			(layer "B.Fab")
			(hide yes)
			(effects
				(font
					(size 0.7 0.7)
					(thickness 0.15)
				)
				(justify left bottom mirror)
			)
		)
		(pad "1" smd circle
			(at 0 0 270)
			(size 1.5 1.5)
			(layers "B.Cu" "B.Mask")
			(net 67 "/JOB_GPIO07")
			(pinfunction "1")
			(pintype "passive")
		)
	)
	(footprint "antmicro-footprints:R_0402_1005Metric"
		(layer "B.Cu")
		(at 129.794 129.54775 180)
		(descr "Resistor SMD 0402")
		(tags "resistor SMD 0402")
		(property "Reference" "R28"
			(at -3.336 -0.42225 0)
			(layer "B.SilkS")
			(effects
				(font
					(size 0.7 0.7)
					(thickness 0.15)
				)
				(justify left bottom mirror)
			)
		)
		(property "Value" "R_1k_0402"
			(at -1.011843 -1.772047 0)
			(layer "B.Fab")
			(effects
				(font
					(size 0.7 0.7)
					(thickness 0.15)
				)
				(justify left bottom mirror)
			)
		)
		(property "Footprint" "antmicro-footprints:R_0402_1005Metric"
			(at 0 0 0)
			(layer "B.Fab")
			(hide yes)
			(effects
				(font
					(size 1.27 1.27)
					(thickness 0.15)
				)
				(justify mirror)
			)
		)
		(property "Datasheet" "https://www.bourns.com/docs/product-datasheets/cr.pdf"
			(at 0 0 0)
			(layer "B.Fab")
			(hide yes)
			(effects
				(font
					(size 1.27 1.27)
					(thickness 0.15)
				)
				(justify mirror)
			)
		)
		(property "Description" "SMD Chip Resistor, 1 kohm, ± 1%, 63 mW, 0402 [1005 Metric], Thick Film, General Purpose"
			(at 0 0 0)
			(layer "B.Fab")
			(hide yes)
			(effects
				(font
					(size 1.27 1.27)
					(thickness 0.15)
				)
				(justify mirror)
			)
		)
		(property "MPN" "CR0402-FX-1001GLF"
			(at 0 0 0)
			(unlocked yes)
			(layer "B.Fab")
			(hide yes)
			(effects
				(font
					(size 1 1)
					(thickness 0.15)
				)
				(justify mirror)
			)
		)
		(property "Manufacturer" "Bourns"
			(at 0 0 0)
			(unlocked yes)
			(layer "B.Fab")
			(hide yes)
			(effects
				(font
					(size 1 1)
					(thickness 0.15)
				)
				(justify mirror)
			)
		)
		(property "License" "Apache-2.0"
			(at 0 0 0)
			(unlocked yes)
			(layer "B.Fab")
			(hide yes)
			(effects
				(font
					(size 1 1)
					(thickness 0.15)
				)
				(justify mirror)
			)
		)
		(property "Author" "Antmicro"
			(at 0 0 0)
			(unlocked yes)
			(layer "B.Fab")
			(hide yes)
			(effects
				(font
					(size 1 1)
					(thickness 0.15)
				)
				(justify mirror)
			)
		)
		(property "Val" "1k"
			(at 0 0 0)
			(unlocked yes)
			(layer "B.Fab")
			(hide yes)
			(effects
				(font
					(size 1 1)
					(thickness 0.15)
				)
				(justify mirror)
			)
		)
		(property "Tolerance" "1%"
			(at 0 0 0)
			(unlocked yes)
			(layer "B.Fab")
			(hide yes)
			(effects
				(font
					(size 1 1)
					(thickness 0.15)
				)
				(justify mirror)
			)
		)
		(property "Public" "False"
			(at 0 0 0)
			(unlocked yes)
			(layer "B.Fab")
			(hide yes)
			(effects
				(font
					(size 1 1)
					(thickness 0.15)
				)
				(justify mirror)
			)
		)
		(sheetname "Root")
		(sheetfile "jetson-orin-baseboard-oculink-expansion.kicad_sch")
		(attr smd dnp)
		(fp_rect
			(start -0.925 0.47)
			(end 0.925 -0.47)
			(stroke
				(width 0.05)
				(type default)
			)
			(fill none)
			(layer "B.CrtYd")
		)
		(fp_rect
			(start -0.5 0.25)
			(end 0.5 -0.25)
			(stroke
				(width 0.15)
				(type solid)
			)
			(fill none)
			(layer "B.Fab")
		)
		(fp_text user "Author: Antmicro"
			(at -0.95 -4.169 0)
			(layer "B.Fab")
			(hide yes)
			(effects
				(font
					(size 0.7 0.7)
					(thickness 0.15)
				)
				(justify left bottom mirror)
			)
		)
		(fp_text user "${REFERENCE}"
			(at -0.95 -3.168 0)
			(layer "B.Fab")
			(hide yes)
			(effects
				(font
					(size 0.7 0.7)
					(thickness 0.15)
				)
				(justify left bottom mirror)
			)
		)
		(fp_text user "License: Apache-2.0"
			(at -0.95 -5.169 0)
			(layer "B.Fab")
			(hide yes)
			(effects
				(font
					(size 0.7 0.7)
					(thickness 0.15)
				)
				(justify left bottom mirror)
			)
		)
		(pad "1" smd roundrect
			(at -0.48 0 180)
			(size 0.59 0.64)
			(layers "B.Cu" "B.Paste" "B.Mask")
			(roundrect_rratio 0.25)
			(net 51 "GND")
			(pintype "passive")
		)
		(pad "2" smd roundrect
			(at 0.48 0 180)
			(size 0.59 0.64)
			(layers "B.Cu" "B.Paste" "B.Mask")
			(roundrect_rratio 0.25)
			(net 101 "/TX_FG1")
			(pintype "passive")
		)
	)
	(footprint "antmicro-footprints:TP_SMD_1.5mm"
		(layer "B.Cu")
		(at 142.4 135.268938 180)
		(property "Reference" "TP9"
			(at -0.8 -10.770882 0)
			(layer "B.SilkS")
			(hide yes)
			(effects
				(font
					(size 0.7 0.7)
					(thickness 0.15)
				)
				(justify left bottom mirror)
			)
		)
		(property "Value" "TP_1.5mm_SMD"
			(at 1.438222 -0.427869 0)
			(layer "B.Fab")
			(effects
				(font
					(size 0.7 0.7)
					(thickness 0.15)
				)
				(justify left bottom mirror)
			)
		)
		(property "Footprint" "antmicro-footprints:TP_SMD_1.5mm"
			(at 0 0 0)
			(layer "B.Fab")
			(hide yes)
			(effects
				(font
					(size 1.27 1.27)
					(thickness 0.15)
				)
				(justify mirror)
			)
		)
		(property "Description" "test point, SMT"
			(at 0 0 0)
			(layer "B.Fab")
			(hide yes)
			(effects
				(font
					(size 1.27 1.27)
					(thickness 0.15)
				)
				(justify mirror)
			)
		)
		(property "MPN" ""
			(at 0 0 0)
			(unlocked yes)
			(layer "B.Fab")
			(hide yes)
			(effects
				(font
					(size 1 1)
					(thickness 0.15)
				)
				(justify mirror)
			)
		)
		(property "Manufacturer" ""
			(at 0 0 0)
			(unlocked yes)
			(layer "B.Fab")
			(hide yes)
			(effects
				(font
					(size 1 1)
					(thickness 0.15)
				)
				(justify mirror)
			)
		)
		(property "Author" "Antmicro"
			(at 0 0 0)
			(unlocked yes)
			(layer "B.Fab")
			(hide yes)
			(effects
				(font
					(size 1 1)
					(thickness 0.15)
				)
				(justify mirror)
			)
		)
		(property "License" "Apache-2.0"
			(at 0 0 0)
			(unlocked yes)
			(layer "B.Fab")
			(hide yes)
			(effects
				(font
					(size 1 1)
					(thickness 0.15)
				)
				(justify mirror)
			)
		)
		(sheetname "Root")
		(sheetfile "jetson-orin-baseboard-oculink-expansion.kicad_sch")
		(attr exclude_from_pos_files exclude_from_bom)
		(fp_circle
			(center 0 0)
			(end 0.85 0)
			(stroke
				(width 0.05)
				(type default)
			)
			(fill none)
			(layer "B.CrtYd")
		)
		(fp_text user "Author: Antmicro"
			(at -0.7 -4.101 0)
			(layer "B.Fab")
			(hide yes)
			(effects
				(font
					(size 0.7 0.7)
					(thickness 0.15)
				)
				(justify left bottom mirror)
			)
		)
		(fp_text user "License: Apache-2.0"
			(at -0.7 -5.301 0)
			(layer "B.Fab")
			(hide yes)
			(effects
				(font
					(size 0.7 0.7)
					(thickness 0.15)
				)
				(justify left bottom mirror)
			)
		)
		(fp_text user "${REFERENCE}"
			(at -0.7 -2.9 0)
			(layer "B.Fab")
			(hide yes)
			(effects
				(font
					(size 0.7 0.7)
					(thickness 0.15)
				)
				(justify left bottom mirror)
			)
		)
		(pad "1" smd circle
			(at 0 0 270)
			(size 1.5 1.5)
			(layers "B.Cu" "B.Mask")
			(net 52 "+5V")
			(pinfunction "1")
			(pintype "passive")
		)
	)
	(footprint "antmicro-footprints:R_0402_1005Metric"
		(layer "B.Cu")
		(at 115.77 125.874)
		(descr "Resistor SMD 0402")
		(tags "resistor SMD 0402")
		(property "Reference" "R42"
			(at -2.916 -0.344 0)
			(layer "B.SilkS")
			(effects
				(font
					(size 0.7 0.7)
					(thickness 0.15)
				)
				(justify right top mirror)
			)
		)
		(property "Value" "R_10k_0402"
			(at -1.011843 -1.772047 0)
			(layer "B.Fab")
			(effects
				(font
					(size 0.7 0.7)
					(thickness 0.15)
				)
				(justify right top mirror)
			)
		)
		(property "Footprint" "antmicro-footprints:R_0402_1005Metric"
			(at 0 0 0)
			(layer "B.Fab")
			(hide yes)
			(effects
				(font
					(size 1.27 1.27)
					(thickness 0.15)
				)
				(justify mirror)
			)
		)
		(property "Datasheet" "https://www.bourns.com/docs/product-datasheets/cr.pdf"
			(at 0 0 0)
			(layer "B.Fab")
			(hide yes)
			(effects
				(font
					(size 1.27 1.27)
					(thickness 0.15)
				)
				(justify mirror)
			)
		)
		(property "Description" "SMD Chip Resistor, 10 kohm, ± 1%, 62.5 mW, 0402 [1005 Metric], Thick Film, General Purpose"
			(at 0 0 0)
			(layer "B.Fab")
			(hide yes)
			(effects
				(font
					(size 1.27 1.27)
					(thickness 0.15)
				)
				(justify mirror)
			)
		)
		(property "MPN" "CR0402-FX-1002GLF"
			(at 0 0 180)
			(unlocked yes)
			(layer "B.Fab")
			(hide yes)
			(effects
				(font
					(size 1 1)
					(thickness 0.15)
				)
				(justify mirror)
			)
		)
		(property "Manufacturer" "Bourns"
			(at 0 0 180)
			(unlocked yes)
			(layer "B.Fab")
			(hide yes)
			(effects
				(font
					(size 1 1)
					(thickness 0.15)
				)
				(justify mirror)
			)
		)
		(property "License" "Apache-2.0"
			(at 0 0 180)
			(unlocked yes)
			(layer "B.Fab")
			(hide yes)
			(effects
				(font
					(size 1 1)
					(thickness 0.15)
				)
				(justify mirror)
			)
		)
		(property "Author" "Antmicro"
			(at 0 0 180)
			(unlocked yes)
			(layer "B.Fab")
			(hide yes)
			(effects
				(font
					(size 1 1)
					(thickness 0.15)
				)
				(justify mirror)
			)
		)
		(property "Val" "10k"
			(at 0 0 180)
			(unlocked yes)
			(layer "B.Fab")
			(hide yes)
			(effects
				(font
					(size 1 1)
					(thickness 0.15)
				)
				(justify mirror)
			)
		)
		(property "Tolerance" "1%"
			(at 0 0 180)
			(unlocked yes)
			(layer "B.Fab")
			(hide yes)
			(effects
				(font
					(size 1 1)
					(thickness 0.15)
				)
				(justify mirror)
			)
		)
		(sheetname "Root")
		(sheetfile "jetson-orin-baseboard-oculink-expansion.kicad_sch")
		(attr smd)
		(fp_rect
			(start -0.925 0.47)
			(end 0.925 -0.47)
			(stroke
				(width 0.05)
				(type default)
			)
			(fill none)
			(layer "B.CrtYd")
		)
		(fp_rect
			(start -0.5 0.25)
			(end 0.5 -0.25)
			(stroke
				(width 0.15)
				(type solid)
			)
			(fill none)
			(layer "B.Fab")
		)
		(fp_text user "${REFERENCE}"
			(at -0.95 -3.168 0)
			(layer "B.Fab")
			(hide yes)
			(effects
				(font
					(size 0.7 0.7)
					(thickness 0.15)
				)
				(justify right top mirror)
			)
		)
		(fp_text user "Author: Antmicro"
			(at -0.95 -4.169 0)
			(layer "B.Fab")
			(hide yes)
			(effects
				(font
					(size 0.7 0.7)
					(thickness 0.15)
				)
				(justify right top mirror)
			)
		)
		(fp_text user "License: Apache-2.0"
			(at -0.95 -5.169 0)
			(layer "B.Fab")
			(hide yes)
			(effects
				(font
					(size 0.7 0.7)
					(thickness 0.15)
				)
				(justify right top mirror)
			)
		)
		(pad "1" smd roundrect
			(at -0.48 0)
			(size 0.59 0.64)
			(layers "B.Cu" "B.Paste" "B.Mask")
			(roundrect_rratio 0.25)
			(net 107 "Net-(U3-SDA)")
			(pintype "passive")
		)
		(pad "2" smd roundrect
			(at 0.48 0)
			(size 0.59 0.64)
			(layers "B.Cu" "B.Paste" "B.Mask")
			(roundrect_rratio 0.25)
			(net 23 "+3V3")
			(pintype "passive")
		)
	)
	(footprint "antmicro-footprints:TP_SMD_1.5mm"
		(layer "B.Cu")
		(at 142.4 137.287876 180)
		(property "Reference" "TP7"
			(at -0.8 -9.862124 0)
			(layer "B.SilkS")
			(hide yes)
			(effects
				(font
					(size 0.7 0.7)
					(thickness 0.15)
				)
				(justify left bottom mirror)
			)
		)
		(property "Value" "TP_1.5mm_SMD"
			(at 1.522222 -1.162028 0)
			(layer "B.Fab")
			(effects
				(font
					(size 0.7 0.7)
					(thickness 0.15)
				)
				(justify left bottom mirror)
			)
		)
		(property "Footprint" "antmicro-footprints:TP_SMD_1.5mm"
			(at 0 0 0)
			(layer "B.Fab")
			(hide yes)
			(effects
				(font
					(size 1.27 1.27)
					(thickness 0.15)
				)
				(justify mirror)
			)
		)
		(property "Description" "test point, SMT"
			(at 0 0 0)
			(layer "B.Fab")
			(hide yes)
			(effects
				(font
					(size 1.27 1.27)
					(thickness 0.15)
				)
				(justify mirror)
			)
		)
		(property "MPN" ""
			(at 0 0 0)
			(unlocked yes)
			(layer "B.Fab")
			(hide yes)
			(effects
				(font
					(size 1 1)
					(thickness 0.15)
				)
				(justify mirror)
			)
		)
		(property "Manufacturer" ""
			(at 0 0 0)
			(unlocked yes)
			(layer "B.Fab")
			(hide yes)
			(effects
				(font
					(size 1 1)
					(thickness 0.15)
				)
				(justify mirror)
			)
		)
		(property "Author" "Antmicro"
			(at 0 0 0)
			(unlocked yes)
			(layer "B.Fab")
			(hide yes)
			(effects
				(font
					(size 1 1)
					(thickness 0.15)
				)
				(justify mirror)
			)
		)
		(property "License" "Apache-2.0"
			(at 0 0 0)
			(unlocked yes)
			(layer "B.Fab")
			(hide yes)
			(effects
				(font
					(size 1 1)
					(thickness 0.15)
				)
				(justify mirror)
			)
		)
		(sheetname "Root")
		(sheetfile "jetson-orin-baseboard-oculink-expansion.kicad_sch")
		(attr exclude_from_pos_files exclude_from_bom)
		(fp_circle
			(center 0 0)
			(end 0.85 0)
			(stroke
				(width 0.05)
				(type default)
			)
			(fill none)
			(layer "B.CrtYd")
		)
		(fp_text user "Author: Antmicro"
			(at -0.7 -4.101 0)
			(layer "B.Fab")
			(hide yes)
			(effects
				(font
					(size 0.7 0.7)
					(thickness 0.15)
				)
				(justify left bottom mirror)
			)
		)
		(fp_text user "${REFERENCE}"
			(at -0.7 -2.9 0)
			(layer "B.Fab")
			(hide yes)
			(effects
				(font
					(size 0.7 0.7)
					(thickness 0.15)
				)
				(justify left bottom mirror)
			)
		)
		(fp_text user "License: Apache-2.0"
			(at -0.7 -5.301 0)
			(layer "B.Fab")
			(hide yes)
			(effects
				(font
					(size 0.7 0.7)
					(thickness 0.15)
				)
				(justify left bottom mirror)
			)
		)
		(pad "1" smd circle
			(at 0 0 270)
			(size 1.5 1.5)
			(layers "B.Cu" "B.Mask")
			(net 59 "/~{PCIE_RST}")
			(pinfunction "1")
			(pintype "passive")
		)
	)
)
